(kicad_pcb
	(version 20241229)
	(generator "pcbnew")
	(generator_version "9.0")
	(general
		(thickness 1.61)
		(legacy_teardrops no)
	)
	(paper "A3")
	(title_block
		(title "RDIMM DDR5 Tester")
		(date "2026-05-21")
		(rev "2.2.0")
		(company "Antmicro")
		(comment 9 "footprints 381-385 of 796")
	)
	(layers
		(0 "F.Cu" signal)
		(4 "In1.Cu" power)
		(6 "In2.Cu" mixed)
		(8 "In3.Cu" power)
		(10 "In4.Cu" mixed)
		(12 "In5.Cu" power)
		(14 "In6.Cu" mixed)
		(16 "In7.Cu" power)
		(18 "In8.Cu" power)
		(20 "In9.Cu" mixed)
		(22 "In10.Cu" power)
		(2 "B.Cu" signal)
		(9 "F.Adhes" user "F.Adhesive")
		(11 "B.Adhes" user "B.Adhesive")
		(13 "F.Paste" user)
		(15 "B.Paste" user)
		(5 "F.SilkS" user "F.Silkscreen")
		(7 "B.SilkS" user "B.Silkscreen")
		(1 "F.Mask" user)
		(3 "B.Mask" user)
		(17 "Dwgs.User" user "User.Drawings")
		(19 "Cmts.User" user "User.Comments")
		(21 "Eco1.User" user "User.Eco1")
		(23 "Eco2.User" user "User.Eco2")
		(25 "Edge.Cuts" user)
		(27 "Margin" user)
		(31 "F.CrtYd" user "F.Courtyard")
		(29 "B.CrtYd" user "B.Courtyard")
		(35 "F.Fab" user)
		(33 "B.Fab" user)
	)
	(footprint "antmicro-footprints:R_0402_1005Metric"
		(layer "B.Cu")
		(at 142.174499 169.399 -90)
		(descr "Resistor SMD 0402")
		(tags "resistor SMD 0402")
		(property "Reference" "R57"
			(at -4.045 -0.505501 90)
			(layer "B.SilkS")
			(effects
				(font
					(size 0.7 0.7)
					(thickness 0.15)
				)
				(justify left bottom mirror)
			)
		)
		(property "Value" "R_22R_0402"
			(at -1.011843 -1.772047 90)
			(layer "B.Fab")
			(effects
				(font
					(size 0.7 0.7)
					(thickness 0.15)
				)
				(justify left bottom mirror)
			)
		)
		(property "Datasheet" "https://www.bourns.com/docs/product-datasheets/cr.pdf"
			(at 0 0 270)
			(layer "F.Fab")
			(hide yes)
			(effects
				(font
					(size 1.27 1.27)
					(thickness 0.15)
				)
			)
		)
		(property "Manufacturer" "Bourns"
			(at 0 0 270)
			(unlocked yes)
			(layer "B.Fab")
			(hide yes)
			(effects
				(font
					(size 1 1)
					(thickness 0.15)
				)
				(justify mirror)
			)
		)
		(property "MPN" "CR0402-FX-22R0GLF"
			(at 0 0 270)
			(unlocked yes)
			(layer "B.Fab")
			(hide yes)
			(effects
				(font
					(size 1 1)
					(thickness 0.15)
				)
				(justify mirror)
			)
		)
		(property "Val" "22R"
			(at 0 0 270)
			(unlocked yes)
			(layer "B.Fab")
			(hide yes)
			(effects
				(font
					(size 1 1)
					(thickness 0.15)
				)
				(justify mirror)
			)
		)
		(property "License" "Apache-2.0"
			(at 0 0 270)
			(unlocked yes)
			(layer "B.Fab")
			(hide yes)
			(effects
				(font
					(size 1 1)
					(thickness 0.15)
				)
				(justify mirror)
			)
		)
		(property "Author" "Antmicro"
			(at 0 0 270)
			(unlocked yes)
			(layer "B.Fab")
			(hide yes)
			(effects
				(font
					(size 1 1)
					(thickness 0.15)
				)
				(justify mirror)
			)
		)
		(property "Tolerance" "1%"
			(at 0 0 270)
			(unlocked yes)
			(layer "B.Fab")
			(hide yes)
			(effects
				(font
					(size 1 1)
					(thickness 0.15)
				)
				(justify mirror)
			)
		)
		(sheetname "/Debug FTDI + VNA/")
		(sheetfile "debug-ftdi.kicad_sch")
		(attr smd exclude_from_bom dnp)
		(fp_rect
			(start -0.925 0.47)
			(end 0.925 -0.47)
			(stroke
				(width 0.05)
				(type default)
			)
			(fill no)
			(layer "B.CrtYd")
		)
		(fp_rect
			(start -0.5 0.25)
			(end 0.5 -0.25)
			(stroke
				(width 0.15)
				(type solid)
			)
			(fill no)
			(layer "B.Fab")
		)
		(fp_text user "Author: Antmicro"
			(at -0.95 -4.169 90)
			(layer "B.Fab")
			(effects
				(font
					(size 0.7 0.7)
					(thickness 0.15)
				)
				(justify left bottom mirror)
			)
		)
		(fp_text user "${REFERENCE}"
			(at -0.95 -3.168 90)
			(layer "B.Fab")
			(effects
				(font
					(size 0.7 0.7)
					(thickness 0.15)
				)
				(justify left bottom mirror)
			)
		)
		(fp_text user "License: Apache-2.0"
			(at -0.95 -5.169 90)
			(layer "B.Fab")
			(effects
				(font
					(size 0.7 0.7)
					(thickness 0.15)
				)
				(justify left bottom mirror)
			)
		)
		(pad "1" smd roundrect
			(at -0.48 0 270)
			(size 0.59 0.64)
			(layers "B.Cu" "B.Mask" "B.Paste")
			(roundrect_rratio 0.25)
			(net 390 "/Debug FTDI + VNA/BDBUS1")
			(pintype "passive")
		)
		(pad "2" smd roundrect
			(at 0.48 0 270)
			(size 0.59 0.64)
			(layers "B.Cu" "B.Mask" "B.Paste")
			(roundrect_rratio 0.25)
			(net 391 "/Debug FTDI + VNA/AUX.TDI")
			(pintype "passive")
		)
	)
	(footprint "antmicro-footprints:R_0402_1005Metric"
		(layer "B.Cu")
		(at 143.224499 169.399 -90)
		(descr "Resistor SMD 0402")
		(tags "resistor SMD 0402")
		(property "Reference" "R58"
			(at -4.045 -0.505501 90)
			(layer "B.SilkS")
			(effects
				(font
					(size 0.7 0.7)
					(thickness 0.15)
				)
				(justify left bottom mirror)
			)
		)
		(property "Value" "R_22R_0402"
			(at -1.011843 -1.772047 90)
			(layer "B.Fab")
			(effects
				(font
					(size 0.7 0.7)
					(thickness 0.15)
				)
				(justify left bottom mirror)
			)
		)
		(property "Datasheet" "https://www.bourns.com/docs/product-datasheets/cr.pdf"
			(at 0 0 270)
			(layer "F.Fab")
			(hide yes)
			(effects
				(font
					(size 1.27 1.27)
					(thickness 0.15)
				)
			)
		)
		(property "Manufacturer" "Bourns"
			(at 0 0 270)
			(unlocked yes)
			(layer "B.Fab")
			(hide yes)
			(effects
				(font
					(size 1 1)
					(thickness 0.15)
				)
				(justify mirror)
			)
		)
		(property "MPN" "CR0402-FX-22R0GLF"
			(at 0 0 270)
			(unlocked yes)
			(layer "B.Fab")
			(hide yes)
			(effects
				(font
					(size 1 1)
					(thickness 0.15)
				)
				(justify mirror)
			)
		)
		(property "Val" "22R"
			(at 0 0 270)
			(unlocked yes)
			(layer "B.Fab")
			(hide yes)
			(effects
				(font
					(size 1 1)
					(thickness 0.15)
				)
				(justify mirror)
			)
		)
		(property "License" "Apache-2.0"
			(at 0 0 270)
			(unlocked yes)
			(layer "B.Fab")
			(hide yes)
			(effects
				(font
					(size 1 1)
					(thickness 0.15)
				)
				(justify mirror)
			)
		)
		(property "Author" "Antmicro"
			(at 0 0 270)
			(unlocked yes)
			(layer "B.Fab")
			(hide yes)
			(effects
				(font
					(size 1 1)
					(thickness 0.15)
				)
				(justify mirror)
			)
		)
		(property "Tolerance" "1%"
			(at 0 0 270)
			(unlocked yes)
			(layer "B.Fab")
			(hide yes)
			(effects
				(font
					(size 1 1)
					(thickness 0.15)
				)
				(justify mirror)
			)
		)
		(sheetname "/Debug FTDI + VNA/")
		(sheetfile "debug-ftdi.kicad_sch")
		(attr smd exclude_from_bom dnp)
		(fp_rect
			(start -0.925 0.47)
			(end 0.925 -0.47)
			(stroke
				(width 0.05)
				(type default)
			)
			(fill no)
			(layer "B.CrtYd")
		)
		(fp_rect
			(start -0.5 0.25)
			(end 0.5 -0.25)
			(stroke
				(width 0.15)
				(type solid)
			)
			(fill no)
			(layer "B.Fab")
		)
		(fp_text user "${REFERENCE}"
			(at -0.95 -3.168 90)
			(layer "B.Fab")
			(effects
				(font
					(size 0.7 0.7)
					(thickness 0.15)
				)
				(justify left bottom mirror)
			)
		)
		(fp_text user "License: Apache-2.0"
			(at -0.95 -5.169 90)
			(layer "B.Fab")
			(effects
				(font
					(size 0.7 0.7)
					(thickness 0.15)
				)
				(justify left bottom mirror)
			)
		)
		(fp_text user "Author: Antmicro"
			(at -0.95 -4.169 90)
			(layer "B.Fab")
			(effects
				(font
					(size 0.7 0.7)
					(thickness 0.15)
				)
				(justify left bottom mirror)
			)
		)
		(pad "1" smd roundrect
			(at -0.48 0 270)
			(size 0.59 0.64)
			(layers "B.Cu" "B.Mask" "B.Paste")
			(roundrect_rratio 0.25)
			(net 392 "/Debug FTDI + VNA/BDBUS2")
			(pintype "passive")
		)
		(pad "2" smd roundrect
			(at 0.48 0 270)
			(size 0.59 0.64)
			(layers "B.Cu" "B.Mask" "B.Paste")
			(roundrect_rratio 0.25)
			(net 406 "/Debug FTDI + VNA/AUX.TDO")
			(pintype "passive")
		)
	)
	(footprint "antmicro-footprints:R_0402_1005Metric"
		(layer "B.Cu")
		(at 145.324499 169.399 -90)
		(descr "Resistor SMD 0402")
		(tags "resistor SMD 0402")
		(property "Reference" "R60"
			(at -4.045 -0.505501 90)
			(layer "B.SilkS")
			(effects
				(font
					(size 0.7 0.7)
					(thickness 0.15)
				)
				(justify left bottom mirror)
			)
		)
		(property "Value" "R_22R_0402"
			(at -1.011843 -1.772047 90)
			(layer "B.Fab")
			(effects
				(font
					(size 0.7 0.7)
					(thickness 0.15)
				)
				(justify left bottom mirror)
			)
		)
		(property "Datasheet" "https://www.bourns.com/docs/product-datasheets/cr.pdf"
			(at 0 0 270)
			(layer "F.Fab")
			(hide yes)
			(effects
				(font
					(size 1.27 1.27)
					(thickness 0.15)
				)
			)
		)
		(property "Manufacturer" "Bourns"
			(at 0 0 270)
			(unlocked yes)
			(layer "B.Fab")
			(hide yes)
			(effects
				(font
					(size 1 1)
					(thickness 0.15)
				)
				(justify mirror)
			)
		)
		(property "MPN" "CR0402-FX-22R0GLF"
			(at 0 0 270)
			(unlocked yes)
			(layer "B.Fab")
			(hide yes)
			(effects
				(font
					(size 1 1)
					(thickness 0.15)
				)
				(justify mirror)
			)
		)
		(property "Val" "22R"
			(at 0 0 270)
			(unlocked yes)
			(layer "B.Fab")
			(hide yes)
			(effects
				(font
					(size 1 1)
					(thickness 0.15)
				)
				(justify mirror)
			)
		)
		(property "License" "Apache-2.0"
			(at 0 0 270)
			(unlocked yes)
			(layer "B.Fab")
			(hide yes)
			(effects
				(font
					(size 1 1)
					(thickness 0.15)
				)
				(justify mirror)
			)
		)
		(property "Author" "Antmicro"
			(at 0 0 270)
			(unlocked yes)
			(layer "B.Fab")
			(hide yes)
			(effects
				(font
					(size 1 1)
					(thickness 0.15)
				)
				(justify mirror)
			)
		)
		(property "Tolerance" "1%"
			(at 0 0 270)
			(unlocked yes)
			(layer "B.Fab")
			(hide yes)
			(effects
				(font
					(size 1 1)
					(thickness 0.15)
				)
				(justify mirror)
			)
		)
		(sheetname "/Debug FTDI + VNA/")
		(sheetfile "debug-ftdi.kicad_sch")
		(attr smd exclude_from_bom dnp)
		(fp_rect
			(start -0.925 0.47)
			(end 0.925 -0.47)
			(stroke
				(width 0.05)
				(type default)
			)
			(fill no)
			(layer "B.CrtYd")
		)
		(fp_rect
			(start -0.5 0.25)
			(end 0.5 -0.25)
			(stroke
				(width 0.15)
				(type solid)
			)
			(fill no)
			(layer "B.Fab")
		)
		(fp_text user "Author: Antmicro"
			(at -0.95 -4.169 90)
			(layer "B.Fab")
			(effects
				(font
					(size 0.7 0.7)
					(thickness 0.15)
				)
				(justify left bottom mirror)
			)
		)
		(fp_text user "License: Apache-2.0"
			(at -0.95 -5.169 90)
			(layer "B.Fab")
			(effects
				(font
					(size 0.7 0.7)
					(thickness 0.15)
				)
				(justify left bottom mirror)
			)
		)
		(fp_text user "${REFERENCE}"
			(at -0.95 -3.168 90)
			(layer "B.Fab")
			(effects
				(font
					(size 0.7 0.7)
					(thickness 0.15)
				)
				(justify left bottom mirror)
			)
		)
		(pad "1" smd roundrect
			(at -0.48 0 270)
			(size 0.59 0.64)
			(layers "B.Cu" "B.Mask" "B.Paste")
			(roundrect_rratio 0.25)
			(net 441 "/Debug FTDI + VNA/I2C_EN")
			(pintype "passive")
		)
		(pad "2" smd roundrect
			(at 0.48 0 270)
			(size 0.59 0.64)
			(layers "B.Cu" "B.Mask" "B.Paste")
			(roundrect_rratio 0.25)
			(net 442 "/Debug FTDI + VNA/AUX.RST")
			(pintype "passive")
		)
	)
	(footprint "antmicro-footprints:R_0402_1005Metric"
		(layer "B.Cu")
		(at 144.274499 169.399 -90)
		(descr "Resistor SMD 0402")
		(tags "resistor SMD 0402")
		(property "Reference" "R59"
			(at -4.045 -0.505501 90)
			(layer "B.SilkS")
			(effects
				(font
					(size 0.7 0.7)
					(thickness 0.15)
				)
				(justify left bottom mirror)
			)
		)
		(property "Value" "R_22R_0402"
			(at -1.011843 -1.772047 90)
			(layer "B.Fab")
			(effects
				(font
					(size 0.7 0.7)
					(thickness 0.15)
				)
				(justify left bottom mirror)
			)
		)
		(property "Datasheet" "https://www.bourns.com/docs/product-datasheets/cr.pdf"
			(at 0 0 270)
			(layer "F.Fab")
			(hide yes)
			(effects
				(font
					(size 1.27 1.27)
					(thickness 0.15)
				)
			)
		)
		(property "Manufacturer" "Bourns"
			(at 0 0 270)
			(unlocked yes)
			(layer "B.Fab")
			(hide yes)
			(effects
				(font
					(size 1 1)
					(thickness 0.15)
				)
				(justify mirror)
			)
		)
		(property "MPN" "CR0402-FX-22R0GLF"
			(at 0 0 270)
			(unlocked yes)
			(layer "B.Fab")
			(hide yes)
			(effects
				(font
					(size 1 1)
					(thickness 0.15)
				)
				(justify mirror)
			)
		)
		(property "Val" "22R"
			(at 0 0 270)
			(unlocked yes)
			(layer "B.Fab")
			(hide yes)
			(effects
				(font
					(size 1 1)
					(thickness 0.15)
				)
				(justify mirror)
			)
		)
		(property "License" "Apache-2.0"
			(at 0 0 270)
			(unlocked yes)
			(layer "B.Fab")
			(hide yes)
			(effects
				(font
					(size 1 1)
					(thickness 0.15)
				)
				(justify mirror)
			)
		)
		(property "Author" "Antmicro"
			(at 0 0 270)
			(unlocked yes)
			(layer "B.Fab")
			(hide yes)
			(effects
				(font
					(size 1 1)
					(thickness 0.15)
				)
				(justify mirror)
			)
		)
		(property "Tolerance" "1%"
			(at 0 0 270)
			(unlocked yes)
			(layer "B.Fab")
			(hide yes)
			(effects
				(font
					(size 1 1)
					(thickness 0.15)
				)
				(justify mirror)
			)
		)
		(sheetname "/Debug FTDI + VNA/")
		(sheetfile "debug-ftdi.kicad_sch")
		(attr smd exclude_from_bom dnp)
		(fp_rect
			(start -0.925 0.47)
			(end 0.925 -0.47)
			(stroke
				(width 0.05)
				(type default)
			)
			(fill no)
			(layer "B.CrtYd")
		)
		(fp_rect
			(start -0.5 0.25)
			(end 0.5 -0.25)
			(stroke
				(width 0.15)
				(type solid)
			)
			(fill no)
			(layer "B.Fab")
		)
		(fp_text user "License: Apache-2.0"
			(at -0.95 -5.169 90)
			(layer "B.Fab")
			(effects
				(font
					(size 0.7 0.7)
					(thickness 0.15)
				)
				(justify left bottom mirror)
			)
		)
		(fp_text user "${REFERENCE}"
			(at -0.95 -3.168 90)
			(layer "B.Fab")
			(effects
				(font
					(size 0.7 0.7)
					(thickness 0.15)
				)
				(justify left bottom mirror)
			)
		)
		(fp_text user "Author: Antmicro"
			(at -0.95 -4.169 90)
			(layer "B.Fab")
			(effects
				(font
					(size 0.7 0.7)
					(thickness 0.15)
				)
				(justify left bottom mirror)
			)
		)
		(pad "1" smd roundrect
			(at -0.48 0 270)
			(size 0.59 0.64)
			(layers "B.Cu" "B.Mask" "B.Paste")
			(roundrect_rratio 0.25)
			(net 407 "/Debug FTDI + VNA/BDBUS3")
			(pintype "passive")
		)
		(pad "2" smd roundrect
			(at 0.48 0 270)
			(size 0.59 0.64)
			(layers "B.Cu" "B.Mask" "B.Paste")
			(roundrect_rratio 0.25)
			(net 408 "/Debug FTDI + VNA/AUX.TMS")
			(pintype "passive")
		)
	)
	(footprint "antmicro-footprints:R_0402_1005Metric"
		(layer "B.Cu")
		(at 140.625 150.025 90)
		(descr "Resistor SMD 0402")
		(tags "resistor SMD 0402")
		(property "Reference" "R101"
			(at -10.375 0.409 90)
			(layer "B.SilkS")
			(effects
				(font
					(size 0.7 0.7)
					(thickness 0.15)
				)
				(justify right bottom mirror)
			)
		)
		(property "Value" "R_10k_0402"
			(at -1.011843 -1.772047 90)
			(layer "B.Fab")
			(effects
				(font
					(size 0.7 0.7)
					(thickness 0.15)
				)
				(justify right bottom mirror)
			)
		)
		(property "Datasheet" "https://www.bourns.com/docs/product-datasheets/cr.pdf"
			(at 0 0 90)
			(layer "F.Fab")
			(hide yes)
			(effects
				(font
					(size 1.27 1.27)
					(thickness 0.15)
				)
			)
		)
		(property "Manufacturer" "Bourns"
			(at 0 0 90)
			(unlocked yes)
			(layer "B.Fab")
			(hide yes)
			(effects
				(font
					(size 1 1)
					(thickness 0.15)
				)
				(justify mirror)
			)
		)
		(property "MPN" "CR0402-FX-1002GLF"
			(at 0 0 90)
			(unlocked yes)
			(layer "B.Fab")
			(hide yes)
			(effects
				(font
					(size 1 1)
					(thickness 0.15)
				)
				(justify mirror)
			)
		)
		(property "Val" "10k"
			(at 0 0 90)
			(unlocked yes)
			(layer "B.Fab")
			(hide yes)
			(effects
				(font
					(size 1 1)
					(thickness 0.15)
				)
				(justify mirror)
			)
		)
		(property "License" "Apache-2.0"
			(at 0 0 90)
			(unlocked yes)
			(layer "B.Fab")
			(hide yes)
			(effects
				(font
					(size 1 1)
					(thickness 0.15)
				)
				(justify mirror)
			)
		)
		(property "Author" "Antmicro"
			(at 0 0 90)
			(unlocked yes)
			(layer "B.Fab")
			(hide yes)
			(effects
				(font
					(size 1 1)
					(thickness 0.15)
				)
				(justify mirror)
			)
		)
		(property "Tolerance" "1%"
			(at 0 0 90)
			(unlocked yes)
			(layer "B.Fab")
			(hide yes)
			(effects
				(font
					(size 1 1)
					(thickness 0.15)
				)
				(justify mirror)
			)
		)
		(sheetname "/Ethernet/")
		(sheetfile "ethernet.kicad_sch")
		(attr smd exclude_from_bom dnp)
		(fp_rect
			(start -0.925 0.47)
			(end 0.925 -0.47)
			(stroke
				(width 0.05)
				(type default)
			)
			(fill no)
			(layer "B.CrtYd")
		)
		(fp_rect
			(start -0.5 0.25)
			(end 0.5 -0.25)
			(stroke
				(width 0.15)
				(type solid)
			)
			(fill no)
			(layer "B.Fab")
		)
		(fp_text user "License: Apache-2.0"
			(at -0.95 -5.169 270)
			(layer "B.Fab")
			(effects
				(font
					(size 0.7 0.7)
					(thickness 0.15)
				)
				(justify left bottom mirror)
			)
		)
		(fp_text user "Author: Antmicro"
			(at -0.95 -4.169 270)
			(layer "B.Fab")
			(effects
				(font
					(size 0.7 0.7)
					(thickness 0.15)
				)
				(justify left bottom mirror)
			)
		)
		(fp_text user "${REFERENCE}"
			(at -0.95 -3.168 270)
			(layer "B.Fab")
			(effects
				(font
					(size 0.7 0.7)
					(thickness 0.15)
				)
				(justify left bottom mirror)
			)
		)
		(pad "1" smd roundrect
			(at -0.48 0 90)
			(size 0.59 0.64)
			(layers "B.Cu" "B.Mask" "B.Paste")
			(roundrect_rratio 0.25)
			(net 393 "/Ethernet/ETH.RXD0")
			(pintype "passive")
		)
		(pad "2" smd roundrect
			(at 0.48 0 90)
			(size 0.59 0.64)
			(layers "B.Cu" "B.Mask" "B.Paste")
			(roundrect_rratio 0.25)
			(net 797 "+1V8")
			(pintype "passive")
		)
	)
)
